(kicad_pcb
	(version 20260206)
	(generator "pcbnew")
	(generator_version "10.0")
	(general
		(thickness 1.6)
		(legacy_teardrops no)
	)
	(paper "A4")
	(title_block
		(title "Bryce Canyon_IOM_M2_16342-2_OCP.brd")
		(comment 1 "Bryce Canyon / footprints 96-102 of 1146")
	)
	(layers
		(0 "F.Cu" signal "TOP")
		(4 "In1.Cu" signal "L2GND")
		(6 "In2.Cu" signal "L3")
		(8 "In3.Cu" signal "L4VCC")
		(10 "In4.Cu" signal "L5VCC")
		(12 "In5.Cu" signal "L6")
		(14 "In6.Cu" signal "L7GND")
		(2 "B.Cu" signal "BOTTOM")
		(9 "F.Adhes" user "F.Adhesive")
		(11 "B.Adhes" user "B.Adhesive")
		(13 "F.Paste" user "Package Geometry/Pastemask Top")
		(15 "B.Paste" user "Package Geometry/Pastemask Bottom")
		(5 "F.SilkS" user "Ref Des/Silkscreen Top")
		(7 "B.SilkS" user "Ref Des/Silkscreen Bottom")
		(1 "F.Mask" user "Board Geometry/Soldermask Top")
		(3 "B.Mask" user "Board Geometry/Soldermask Bottom")
		(17 "Dwgs.User" user "User.Drawings")
		(19 "Cmts.User" user "User.Comments")
		(21 "Eco1.User" user "User.Eco1")
		(23 "Eco2.User" user "User.Eco2")
		(25 "Edge.Cuts" user "Board Geometry/Outline")
		(27 "Margin" user)
		(31 "F.CrtYd" user "Package Geometry/Place Bound Top")
		(29 "B.CrtYd" user "Package Geometry/Place Bound Bottom")
		(35 "F.Fab" user "Ref Des/Assembly Top")
		(33 "B.Fab" user "Ref Des/Assembly Bottom")
	)
	(footprint ""
		(layer "F.Cu")
		(at 95.06458 -13.4112 90)
		(property "Reference" "D15"
			(at 0 0 90)
			(layer "F.SilkS")
			(hide yes)
			(effects
				(font
					(size 1.27 1.27)
				)
			)
		)
		(property "Value" "PESD5V0S1BL-1-GP"
			(at 1.8923 -1.5621 90)
			(unlocked yes)
			(layer "F.Fab")
			(hide yes)
			(effects
				(font
					(size 1.016 1.016)
					(thickness 0.1524)
				)
			)
		)
		(property "Device Type" "SOD882-10D6-1H20"
			(at 1.8923 -3.0861 90)
			(unlocked yes)
			(layer "F.Fab")
			(hide yes)
			(effects
				(font
					(size 1.016 1.016)
					(thickness 0.1524)
				)
			)
		)
		(duplicate_pad_numbers_are_jumpers no)
		(fp_line
			(start -0.3048 -0.9271)
			(end 0.3048 -0.9271)
			(stroke
				(width 0.254)
				(type default)
			)
			(layer "F.SilkS")
		)
		(fp_rect
			(start -0.2921 0.4953)
			(end 0.2921 -0.4953)
			(stroke
				(width 0)
				(type default)
			)
			(fill no)
			(layer "F.CrtYd")
		)
		(fp_poly
			(pts
				(xy -0.4318 0.8001) (xy -0.4318 -0.266192) (xy -0.2921 -0.266192) (xy -0.2921 0.4953) (xy 0.2921 0.4953)
				(xy 0.2921 -0.4953) (xy -0.2921 -0.4953) (xy -0.2921 -0.2667) (xy -0.4318 -0.2667) (xy -0.4318 -0.8001)
				(xy 0.4318 -0.8001) (xy 0.4318 0.8001)
			)
			(stroke
				(width 0)
				(type default)
			)
			(fill no)
			(layer "F.CrtYd")
		)
		(fp_rect
			(start -0.4318 0.8001)
			(end 0.4318 -0.8001)
			(stroke
				(width 0)
				(type default)
			)
			(fill no)
			(layer "F.Fab")
		)
		(pad "1" smd custom
			(at 0 -0.4445 90)
			(size 0.1143 0.1143)
			(layers "F.Cu" "F.Mask" "F.Paste")
			(net "I2C_DEBUG_SDA")
			(options
				(clearance outline)
				(anchor circle)
			)
			(primitives
				(gr_poly
					(pts
						(arc
							(start -0.2032 0.2286)
							(mid -0.275042 0.198842)
							(end -0.3048 0.127)
						)
						(arc
							(start -0.3048 -0.127)
							(mid -0.275042 -0.198842)
							(end -0.2032 -0.2286)
						)
						(arc
							(start 0.2032 -0.2286)
							(mid 0.275042 -0.198842)
							(end 0.3048 -0.127)
						)
						(arc
							(start 0.3048 0.127)
							(mid 0.275042 0.198842)
							(end 0.2032 0.2286)
						)
					)
					(width 0)
					(fill yes)
				)
			)
		)
		(pad "2" smd custom
			(at 0 0.4445 90)
			(size 0.1143 0.1143)
			(layers "F.Cu" "F.Mask" "F.Paste")
			(net "GND")
			(options
				(clearance outline)
				(anchor circle)
			)
			(primitives
				(gr_poly
					(pts
						(arc
							(start 0.2032 -0.2286)
							(mid 0.275042 -0.198842)
							(end 0.3048 -0.127)
						)
						(arc
							(start 0.3048 0.127)
							(mid 0.275042 0.198842)
							(end 0.2032 0.2286)
						)
						(arc
							(start -0.2032 0.2286)
							(mid -0.275042 0.198842)
							(end -0.3048 0.127)
						)
						(arc
							(start -0.3048 -0.127)
							(mid -0.275042 -0.198842)
							(end -0.2032 -0.2286)
						)
					)
					(width 0)
					(fill yes)
				)
			)
		)
	)
	(footprint ""
		(layer "F.Cu")
		(at 225.390964 -96.854264 90)
		(property "Reference" "R838"
			(at 0 0 90)
			(layer "F.SilkS")
			(hide yes)
			(effects
				(font
					(size 1.27 1.27)
				)
			)
		)
		(property "Value" "3D01R5F-GP"
			(at 0 -8.9535 90)
			(unlocked yes)
			(layer "F.Fab")
			(hide yes)
			(effects
				(font
					(size 1.27 1.016)
					(thickness 0.1524)
				)
			)
		)
		(property "Device Type" "R805H24"
			(at 0 -10.6299 90)
			(unlocked yes)
			(layer "F.Fab")
			(hide yes)
			(effects
				(font
					(size 1.27 1.016)
					(thickness 0.1524)
				)
			)
		)
		(duplicate_pad_numbers_are_jumpers no)
		(fp_line
			(start 0.889 -1.7018)
			(end -0.889 -1.7018)
			(stroke
				(width 0.1524)
				(type default)
			)
			(layer "F.SilkS")
		)
		(fp_line
			(start 0.889 -1.7018)
			(end 0.889 -0.381)
			(stroke
				(width 0.1524)
				(type default)
			)
			(layer "F.SilkS")
		)
		(fp_line
			(start -0.889 -1.7018)
			(end -0.889 0.2794)
			(stroke
				(width 0.1524)
				(type default)
			)
			(layer "F.SilkS")
		)
		(fp_line
			(start -0.889 0.0762)
			(end -0.889 1.7018)
			(stroke
				(width 0.1524)
				(type default)
			)
			(layer "F.SilkS")
		)
		(fp_line
			(start 0.889 1.7018)
			(end 0.889 -0.508)
			(stroke
				(width 0.1524)
				(type default)
			)
			(layer "F.SilkS")
		)
		(fp_line
			(start -0.889 1.7018)
			(end 0.889 1.7018)
			(stroke
				(width 0.1524)
				(type default)
			)
			(layer "F.SilkS")
		)
		(fp_poly
			(pts
				(xy 0.9652 -1.778) (xy 0.9652 1.778) (xy -0.9652 1.778) (xy -0.9652 -1.778)
			)
			(stroke
				(width 0)
				(type default)
			)
			(fill no)
			(layer "F.CrtYd")
		)
		(fp_rect
			(start -0.9652 1.778)
			(end 0.9652 -1.778)
			(stroke
				(width 0)
				(type default)
			)
			(fill no)
			(layer "F.Fab")
		)
		(pad "1" smd rect
			(at 0 -0.9652 90)
			(size 1.397 1.143)
			(layers "F.Cu" "F.Mask" "F.Paste")
			(net "GND")
		)
		(pad "2" smd rect
			(at 0 0.9652 90)
			(size 1.397 1.143)
			(layers "F.Cu" "F.Mask" "F.Paste")
			(net "P3V3_M2_SNB")
		)
	)
	(footprint ""
		(layer "F.Cu")
		(at 54.539642 -166.064184)
		(property "Reference" "R779"
			(at 0 0 0)
			(layer "F.SilkS")
			(hide yes)
			(effects
				(font
					(size 1.27 1.27)
				)
			)
		)
		(property "Value" "1KR2F-3-GP"
			(at 0.064008 -3.993896 0)
			(unlocked yes)
			(layer "F.Fab")
			(hide yes)
			(effects
				(font
					(size 1.016 1.016)
					(thickness 0.1524)
				)
			)
		)
		(property "Device Type" "R402H16"
			(at 0.064008 -5.517896 0)
			(unlocked yes)
			(layer "F.Fab")
			(hide yes)
			(effects
				(font
					(size 1.016 1.016)
					(thickness 0.1524)
				)
			)
		)
		(duplicate_pad_numbers_are_jumpers no)
		(fp_line
			(start -0.508 -0.9398)
			(end -0.508 0.9398)
			(stroke
				(width 0.1524)
				(type default)
			)
			(layer "F.SilkS")
		)
		(fp_line
			(start 0.508 -0.9398)
			(end -0.508 -0.9398)
			(stroke
				(width 0.1524)
				(type default)
			)
			(layer "F.SilkS")
		)
		(fp_rect
			(start -0.508 0.9398)
			(end 0.508 -0.9398)
			(stroke
				(width 0)
				(type default)
			)
			(fill no)
			(layer "F.CrtYd")
		)
		(fp_rect
			(start -0.508 0.9398)
			(end 0.508 -0.9398)
			(stroke
				(width 0)
				(type default)
			)
			(fill no)
			(layer "F.Fab")
		)
		(pad "1" smd custom
			(at 0 -0.4445)
			(size 0.1397 0.1397)
			(layers "F.Cu" "F.Mask" "F.Paste")
			(net "ADC_P2V5_STBY")
			(options
				(clearance outline)
				(anchor circle)
			)
			(primitives
				(gr_poly
					(pts
						(arc
							(start -0.1778 -0.2794)
							(mid -0.249642 -0.249642)
							(end -0.2794 -0.1778)
						)
						(arc
							(start -0.2794 0.1778)
							(mid -0.249642 0.249642)
							(end -0.1778 0.2794)
						)
						(arc
							(start 0.1778 0.2794)
							(mid 0.249642 0.249642)
							(end 0.2794 0.1778)
						)
						(arc
							(start 0.2794 -0.1778)
							(mid 0.249642 -0.249642)
							(end 0.1778 -0.2794)
						)
					)
					(width 0)
					(fill yes)
				)
			)
		)
		(pad "2" smd custom
			(at 0 0.4445)
			(size 0.1397 0.1397)
			(layers "F.Cu" "F.Mask" "F.Paste")
			(net "GND")
			(options
				(clearance outline)
				(anchor circle)
			)
			(primitives
				(gr_poly
					(pts
						(arc
							(start -0.1778 -0.2794)
							(mid -0.249642 -0.249642)
							(end -0.2794 -0.1778)
						)
						(arc
							(start -0.2794 0.1778)
							(mid -0.249642 0.249642)
							(end -0.1778 0.2794)
						)
						(arc
							(start 0.1778 0.2794)
							(mid 0.249642 0.249642)
							(end 0.2794 0.1778)
						)
						(arc
							(start 0.2794 -0.1778)
							(mid 0.249642 -0.249642)
							(end 0.1778 -0.2794)
						)
					)
					(width 0)
					(fill yes)
				)
			)
		)
	)
	(footprint ""
		(layer "F.Cu")
		(at 65.679828 -163.118546 -90)
		(property "Reference" "R76"
			(at 0 0 270)
			(layer "F.SilkS")
			(hide yes)
			(effects
				(font
					(size 1.27 1.27)
				)
			)
		)
		(property "Value" "47KR2F-GP"
			(at 0.064008 -3.993896 270)
			(unlocked yes)
			(layer "F.Fab")
			(hide yes)
			(effects
				(font
					(size 1.016 1.016)
					(thickness 0.1524)
				)
			)
		)
		(property "Device Type" "R402H16"
			(at 0.064008 -5.517896 270)
			(unlocked yes)
			(layer "F.Fab")
			(hide yes)
			(effects
				(font
					(size 1.016 1.016)
					(thickness 0.1524)
				)
			)
		)
		(duplicate_pad_numbers_are_jumpers no)
		(fp_line
			(start -0.508 -0.9398)
			(end -0.508 0.9398)
			(stroke
				(width 0.1524)
				(type default)
			)
			(layer "F.SilkS")
		)
		(fp_line
			(start 0.508 -0.9398)
			(end -0.508 -0.9398)
			(stroke
				(width 0.1524)
				(type default)
			)
			(layer "F.SilkS")
		)
		(fp_rect
			(start -0.508 0.9398)
			(end 0.508 -0.9398)
			(stroke
				(width 0)
				(type default)
			)
			(fill no)
			(layer "F.CrtYd")
		)
		(fp_rect
			(start -0.508 0.9398)
			(end 0.508 -0.9398)
			(stroke
				(width 0)
				(type default)
			)
			(fill no)
			(layer "F.Fab")
		)
		(pad "1" smd custom
			(at 0 -0.4445 270)
			(size 0.1397 0.1397)
			(layers "F.Cu" "F.Mask" "F.Paste")
			(net "FM_TPM_PRSNT_RST_N")
			(options
				(clearance outline)
				(anchor circle)
			)
			(primitives
				(gr_poly
					(pts
						(arc
							(start -0.1778 -0.2794)
							(mid -0.249642 -0.249642)
							(end -0.2794 -0.1778)
						)
						(arc
							(start -0.2794 0.1778)
							(mid -0.249642 0.249642)
							(end -0.1778 0.2794)
						)
						(arc
							(start 0.1778 0.2794)
							(mid 0.249642 0.249642)
							(end 0.2794 0.1778)
						)
						(arc
							(start 0.2794 -0.1778)
							(mid 0.249642 -0.249642)
							(end 0.1778 -0.2794)
						)
					)
					(width 0)
					(fill yes)
				)
			)
		)
		(pad "2" smd custom
			(at 0 0.4445 270)
			(size 0.1397 0.1397)
			(layers "F.Cu" "F.Mask" "F.Paste")
			(net "FM_TPM_PRSNT_RST_N_R")
			(options
				(clearance outline)
				(anchor circle)
			)
			(primitives
				(gr_poly
					(pts
						(arc
							(start -0.1778 -0.2794)
							(mid -0.249642 -0.249642)
							(end -0.2794 -0.1778)
						)
						(arc
							(start -0.2794 0.1778)
							(mid -0.249642 0.249642)
							(end -0.1778 0.2794)
						)
						(arc
							(start 0.1778 0.2794)
							(mid 0.249642 0.249642)
							(end 0.2794 0.1778)
						)
						(arc
							(start 0.2794 -0.1778)
							(mid 0.249642 -0.249642)
							(end 0.1778 -0.2794)
						)
					)
					(width 0)
					(fill yes)
				)
			)
		)
	)
	(footprint ""
		(layer "F.Cu")
		(at 62.6618 -172.1104)
		(property "Reference" "R74"
			(at 0 0 0)
			(layer "F.SilkS")
			(hide yes)
			(effects
				(font
					(size 1.27 1.27)
				)
			)
		)
		(property "Value" "0R2J-2-GP"
			(at 0.064008 -3.993896 0)
			(unlocked yes)
			(layer "F.Fab")
			(hide yes)
			(effects
				(font
					(size 1.016 1.016)
					(thickness 0.1524)
				)
			)
		)
		(property "Device Type" "R402H16"
			(at 0.064008 -5.517896 0)
			(unlocked yes)
			(layer "F.Fab")
			(hide yes)
			(effects
				(font
					(size 1.016 1.016)
					(thickness 0.1524)
				)
			)
		)
		(duplicate_pad_numbers_are_jumpers no)
		(fp_line
			(start -0.508 -0.9398)
			(end -0.508 0.9398)
			(stroke
				(width 0.1524)
				(type default)
			)
			(layer "F.SilkS")
		)
		(fp_line
			(start 0.508 -0.9398)
			(end -0.508 -0.9398)
			(stroke
				(width 0.1524)
				(type default)
			)
			(layer "F.SilkS")
		)
		(fp_rect
			(start -0.508 0.9398)
			(end 0.508 -0.9398)
			(stroke
				(width 0)
				(type default)
			)
			(fill no)
			(layer "F.CrtYd")
		)
		(fp_rect
			(start -0.508 0.9398)
			(end 0.508 -0.9398)
			(stroke
				(width 0)
				(type default)
			)
			(fill no)
			(layer "F.Fab")
		)
		(pad "1" smd custom
			(at 0 -0.4445)
			(size 0.1397 0.1397)
			(layers "F.Cu" "F.Mask" "F.Paste")
			(net "FM_TPM_PRSNT_RST_N_C")
			(options
				(clearance outline)
				(anchor circle)
			)
			(primitives
				(gr_poly
					(pts
						(arc
							(start -0.1778 -0.2794)
							(mid -0.249642 -0.249642)
							(end -0.2794 -0.1778)
						)
						(arc
							(start -0.2794 0.1778)
							(mid -0.249642 0.249642)
							(end -0.1778 0.2794)
						)
						(arc
							(start 0.1778 0.2794)
							(mid 0.249642 0.249642)
							(end 0.2794 0.1778)
						)
						(arc
							(start 0.2794 -0.1778)
							(mid 0.249642 -0.249642)
							(end 0.1778 -0.2794)
						)
					)
					(width 0)
					(fill yes)
				)
			)
		)
		(pad "2" smd custom
			(at 0 0.4445)
			(size 0.1397 0.1397)
			(layers "F.Cu" "F.Mask" "F.Paste")
			(net "FM_TPM_PRSNT_RST_N")
			(options
				(clearance outline)
				(anchor circle)
			)
			(primitives
				(gr_poly
					(pts
						(arc
							(start -0.1778 -0.2794)
							(mid -0.249642 -0.249642)
							(end -0.2794 -0.1778)
						)
						(arc
							(start -0.2794 0.1778)
							(mid -0.249642 0.249642)
							(end -0.1778 0.2794)
						)
						(arc
							(start 0.1778 0.2794)
							(mid 0.249642 0.249642)
							(end 0.2794 0.1778)
						)
						(arc
							(start 0.2794 -0.1778)
							(mid 0.249642 -0.249642)
							(end 0.1778 -0.2794)
						)
					)
					(width 0)
					(fill yes)
				)
			)
		)
	)
	(footprint ""
		(layer "F.Cu")
		(at 78.122018 -83.754468 90)
		(property "Reference" "VIA5"
			(at 0 0 90)
			(layer "F.SilkS")
			(hide yes)
			(effects
				(font
					(size 1.27 1.27)
				)
			)
		)
		(property "Value" "85OHM-8L-1D6MM-L16L18-GP"
			(at 4.064 0.6096 90)
			(unlocked yes)
			(layer "F.Fab")
			(hide yes)
			(effects
				(font
					(size 1.016 1.016)
					(thickness 0.1524)
				)
			)
		)
		(property "Device Type" "VIA-PCIE-4P-368076"
			(at 4.064 -0.9144 90)
			(unlocked yes)
			(layer "F.Fab")
			(hide yes)
			(effects
				(font
					(size 1.016 1.016)
					(thickness 0.1524)
				)
			)
		)
		(duplicate_pad_numbers_are_jumpers no)
		(fp_rect
			(start -1.8415 0.381)
			(end 1.8415 -0.381)
			(stroke
				(width 0)
				(type default)
			)
			(fill no)
			(layer "F.CrtYd")
		)
		(fp_rect
			(start -1.8415 0.381)
			(end 1.8415 -0.381)
			(stroke
				(width 0)
				(type default)
			)
			(fill no)
			(layer "F.Fab")
		)
		(pad "1" thru_hole circle
			(at -1.4605 0 90)
			(size 0.508 0.508)
			(drill 0.254)
			(layers "*.Cu" "*.Mask")
			(remove_unused_layers no)
			(net "GND")
			(clearance 0.127)
			(thermal_gap 0.127)
		)
		(pad "2" thru_hole circle
			(at -0.4445 0 90)
			(size 0.508 0.508)
			(drill 0.254)
			(layers "*.Cu" "*.Mask")
			(remove_unused_layers no)
			(net "PCIE_COMP_TO_IOM_20_DP")
			(clearance 0.127)
			(thermal_gap 0.127)
		)
		(pad "3" thru_hole circle
			(at 0.4445 0 90)
			(size 0.508 0.508)
			(drill 0.254)
			(layers "*.Cu" "*.Mask")
			(remove_unused_layers no)
			(net "PCIE_COMP_TO_IOM_20_DN")
			(clearance 0.127)
			(thermal_gap 0.127)
		)
		(pad "4" thru_hole circle
			(at 1.4605 0 90)
			(size 0.508 0.508)
			(drill 0.254)
			(layers "*.Cu" "*.Mask")
			(remove_unused_layers no)
			(net "GND")
			(clearance 0.127)
			(thermal_gap 0.127)
		)
	)
	(footprint ""
		(layer "F.Cu")
		(at 45.409104 -161.231072 180)
		(property "Reference" "R180"
			(at 0 0 180)
			(layer "F.SilkS")
			(hide yes)
			(effects
				(font
					(size 1.27 1.27)
				)
			)
		)
		(property "Value" "2K2R2F-GP"
			(at 0.064008 -3.993896 180)
			(unlocked yes)
			(layer "F.Fab")
			(hide yes)
			(effects
				(font
					(size 1.016 1.016)
					(thickness 0.1524)
				)
			)
		)
		(property "Device Type" "R402H16"
			(at 0.064008 -5.517896 180)
			(unlocked yes)
			(layer "F.Fab")
			(hide yes)
			(effects
				(font
					(size 1.016 1.016)
					(thickness 0.1524)
				)
			)
		)
		(duplicate_pad_numbers_are_jumpers no)
		(fp_line
			(start 0.508 -0.9398)
			(end -0.508 -0.9398)
			(stroke
				(width 0.1524)
				(type default)
			)
			(layer "F.SilkS")
		)
		(fp_line
			(start -0.508 -0.9398)
			(end -0.508 0.9398)
			(stroke
				(width 0.1524)
				(type default)
			)
			(layer "F.SilkS")
		)
		(fp_rect
			(start -0.508 0.9398)
			(end 0.508 -0.9398)
			(stroke
				(width 0)
				(type default)
			)
			(fill no)
			(layer "F.CrtYd")
		)
		(fp_rect
			(start -0.508 0.9398)
			(end 0.508 -0.9398)
			(stroke
				(width 0)
				(type default)
			)
			(fill no)
			(layer "F.Fab")
		)
		(pad "1" smd custom
			(at 0 -0.4445 180)
			(size 0.1397 0.1397)
			(layers "F.Cu" "F.Mask" "F.Paste")
			(net "I2C_DPB_SDA_OUT")
			(options
				(clearance outline)
				(anchor circle)
			)
			(primitives
				(gr_poly
					(pts
						(arc
							(start -0.1778 -0.2794)
							(mid -0.249642 -0.249642)
							(end -0.2794 -0.1778)
						)
						(arc
							(start -0.2794 0.1778)
							(mid -0.249642 0.249642)
							(end -0.1778 0.2794)
						)
						(arc
							(start 0.1778 0.2794)
							(mid 0.249642 0.249642)
							(end 0.2794 0.1778)
						)
						(arc
							(start 0.2794 -0.1778)
							(mid 0.249642 -0.249642)
							(end 0.1778 -0.2794)
						)
					)
					(width 0)
					(fill yes)
				)
			)
		)
		(pad "2" smd custom
			(at 0 0.4445 180)
			(size 0.1397 0.1397)
			(layers "F.Cu" "F.Mask" "F.Paste")
			(net "P3V3_STBY")
			(options
				(clearance outline)
				(anchor circle)
			)
			(primitives
				(gr_poly
					(pts
						(arc
							(start -0.1778 -0.2794)
							(mid -0.249642 -0.249642)
							(end -0.2794 -0.1778)
						)
						(arc
							(start -0.2794 0.1778)
							(mid -0.249642 0.249642)
							(end -0.1778 0.2794)
						)
						(arc
							(start 0.1778 0.2794)
							(mid 0.249642 0.249642)
							(end 0.2794 0.1778)
						)
						(arc
							(start 0.2794 -0.1778)
							(mid 0.249642 -0.249642)
							(end 0.1778 -0.2794)
						)
					)
					(width 0)
					(fill yes)
				)
			)
		)
	)
)
